(kicad_pcb
	(version 20241229)
	(generator "pcbnew")
	(generator_version "9.0")
	(general
		(thickness 1.294)
		(legacy_teardrops no)
	)
	(paper "A3")
	(title_block
		(title "Kintex 410T devboard")
		(date "2024-04-03")
		(rev "1.1.2")
		(comment 9 "footprints 106-110 of 975")
	)
	(layers
		(0 "F.Cu" mixed)
		(4 "In1.Cu" power)
		(6 "In2.Cu" power)
		(8 "In3.Cu" mixed)
		(10 "In4.Cu" power)
		(12 "In5.Cu" mixed)
		(14 "In6.Cu" power)
		(16 "In7.Cu" mixed)
		(18 "In8.Cu" power)
		(2 "B.Cu" mixed)
		(9 "F.Adhes" user "F.Adhesive")
		(11 "B.Adhes" user "B.Adhesive")
		(13 "F.Paste" user)
		(15 "B.Paste" user)
		(5 "F.SilkS" user "F.Silkscreen")
		(7 "B.SilkS" user "B.Silkscreen")
		(1 "F.Mask" user)
		(3 "B.Mask" user)
		(17 "Dwgs.User" user "User.Drawings")
		(19 "Cmts.User" user "User.Comments")
		(21 "Eco1.User" user "User.Eco1")
		(23 "Eco2.User" user "User.Eco2")
		(25 "Edge.Cuts" user)
		(27 "Margin" user)
		(31 "F.CrtYd" user "F.Courtyard")
		(29 "B.CrtYd" user "B.Courtyard")
		(35 "F.Fab" user)
		(33 "B.Fab" user)
	)
	(footprint "antmicro-footprints:C_0603_1608Metric"
		(layer "F.Cu")
		(at 160.55 164.05)
		(descr "Capacitor SMD 0603")
		(tags "capacitor 0603")
		(property "Reference" "C327"
			(at 0.95 0.4 0)
			(layer "F.SilkS")
			(effects
				(font
					(size 0.7 0.7)
					(thickness 0.15)
				)
				(justify left bottom)
			)
		)
		(property "Value" "C_22u_0603"
			(at 0 1.6 0)
			(layer "F.Fab")
			(effects
				(font
					(size 0.7 0.7)
					(thickness 0.15)
				)
				(justify left bottom)
			)
		)
		(property "Description" "SMD Multilayer Ceramic Capacitor, 22 µF, 6.3 V, 0603 [1608 Metric], ± 20%, X5R, GRM Series"
			(at 0 0 0)
			(layer "F.Fab")
			(hide yes)
			(effects
				(font
					(size 1.27 1.27)
					(thickness 0.15)
				)
			)
		)
		(property "Author" "Antmicro"
			(at 0 0 0)
			(layer "F.Fab")
			(hide yes)
			(effects
				(font
					(size 1 1)
					(thickness 0.15)
				)
			)
		)
		(property "Dielectric" ""
			(at 0 0 0)
			(layer "F.Fab")
			(hide yes)
			(effects
				(font
					(size 1 1)
					(thickness 0.15)
				)
			)
		)
		(property "License" "Apache-2.0"
			(at 0 0 0)
			(layer "F.Fab")
			(hide yes)
			(effects
				(font
					(size 1 1)
					(thickness 0.15)
				)
			)
		)
		(property "MPN" "GRM188R60J226MEA0D"
			(at 0 0 0)
			(layer "F.Fab")
			(hide yes)
			(effects
				(font
					(size 1 1)
					(thickness 0.15)
				)
			)
		)
		(property "Manufacturer" "Murata"
			(at 0 0 0)
			(layer "F.Fab")
			(hide yes)
			(effects
				(font
					(size 1 1)
					(thickness 0.15)
				)
			)
		)
		(property "Val" "22u"
			(at 0 0 0)
			(layer "F.Fab")
			(hide yes)
			(effects
				(font
					(size 1 1)
					(thickness 0.15)
				)
			)
		)
		(property "Voltage" ""
			(at 0 0 0)
			(layer "F.Fab")
			(hide yes)
			(effects
				(font
					(size 1 1)
					(thickness 0.15)
				)
			)
		)
		(sheetname "DC-DC Converters")
		(sheetfile "dc-dc.kicad_sch")
		(attr smd)
		(fp_line
			(start -0.15 -0.4)
			(end 0.15 -0.4)
			(stroke
				(width 0.15)
				(type solid)
			)
			(layer "F.SilkS")
		)
		(fp_line
			(start -0.15 0.4)
			(end 0.15 0.4)
			(stroke
				(width 0.15)
				(type solid)
			)
			(layer "F.SilkS")
		)
		(fp_rect
			(start -1.25 -0.65)
			(end 1.25 0.65)
			(stroke
				(width 0.05)
				(type solid)
			)
			(fill no)
			(layer "F.CrtYd")
		)
		(fp_rect
			(start -0.8 -0.4)
			(end 0.8 0.4)
			(stroke
				(width 0.15)
				(type solid)
			)
			(fill no)
			(layer "F.Fab")
		)
		(pad "1" smd roundrect
			(at -0.7 0)
			(size 0.8 1)
			(layers "F.Cu" "F.Mask" "F.Paste")
			(roundrect_rratio 0.2)
			(net 1 "GND")
			(pintype "passive")
		)
		(pad "2" smd roundrect
			(at 0.7 0)
			(size 0.8 1)
			(layers "F.Cu" "F.Mask" "F.Paste")
			(roundrect_rratio 0.2)
			(net 734 "/DC-DC Converters/1V8_local")
			(pintype "passive")
		)
	)
	(footprint "antmicro-footprints:DHVQFN-14-1EP_2.5x3mm"
		(layer "F.Cu")
		(at 239.3 130.8 180)
		(property "Reference" "U22"
			(at -1.375 1.65 270)
			(layer "F.SilkS")
			(effects
				(font
					(size 0.7 0.7)
					(thickness 0.15)
				)
				(justify left bottom)
			)
		)
		(property "Value" "TXU0304BQAR"
			(at 0 2.898 180)
			(layer "F.Fab")
			(effects
				(font
					(size 0.7 0.7)
					(thickness 0.15)
				)
				(justify left bottom)
			)
		)
		(property "Description" "Logic translator/level shifter"
			(at 0 0 180)
			(layer "F.Fab")
			(hide yes)
			(effects
				(font
					(size 1.27 1.27)
					(thickness 0.15)
				)
			)
		)
		(property "Author" "Antmicro"
			(at 478.6 261.6 0)
			(layer "F.Fab")
			(hide yes)
			(effects
				(font
					(size 1 1)
					(thickness 0.15)
				)
			)
		)
		(property "License" "Apache-2.0"
			(at 478.6 261.6 0)
			(layer "F.Fab")
			(hide yes)
			(effects
				(font
					(size 1 1)
					(thickness 0.15)
				)
			)
		)
		(property "MPN" "TXU0304BQAR"
			(at 478.6 261.6 0)
			(layer "F.Fab")
			(hide yes)
			(effects
				(font
					(size 1 1)
					(thickness 0.15)
				)
			)
		)
		(property "Manufacturer" "Texas Instruments"
			(at 478.6 261.6 0)
			(layer "F.Fab")
			(hide yes)
			(effects
				(font
					(size 1 1)
					(thickness 0.15)
				)
			)
		)
		(sheetname "USB PHY")
		(sheetfile "usb-phy.kicad_sch")
		(attr smd)
		(fp_line
			(start 1.35 1.6)
			(end 1.35 1.249)
			(stroke
				(width 0.15)
				(type solid)
			)
			(layer "F.SilkS")
		)
		(fp_line
			(start 1.35 -1.601)
			(end 1.35 -1.25)
			(stroke
				(width 0.15)
				(type solid)
			)
			(layer "F.SilkS")
		)
		(fp_line
			(start 1.35 -1.601)
			(end 0.494 -1.601)
			(stroke
				(width 0.15)
				(type solid)
			)
			(layer "F.SilkS")
		)
		(fp_line
			(start 0.494 1.6)
			(end 1.35 1.6)
			(stroke
				(width 0.15)
				(type solid)
			)
			(layer "F.SilkS")
		)
		(fp_line
			(start -1.35 -1.601)
			(end -1.35 -1.25)
			(stroke
				(width 0.15)
				(type solid)
			)
			(layer "F.SilkS")
		)
		(fp_line
			(start -1.351 1.6)
			(end -0.5 1.6)
			(stroke
				(width 0.15)
				(type solid)
			)
			(layer "F.SilkS")
		)
		(fp_line
			(start -1.351 1.6)
			(end -1.351 1.249)
			(stroke
				(width 0.15)
				(type solid)
			)
			(layer "F.SilkS")
		)
		(fp_line
			(start -1.351 -1.601)
			(end -0.5 -1.601)
			(stroke
				(width 0.15)
				(type solid)
			)
			(layer "F.SilkS")
		)
		(fp_circle
			(center -0.7 -1.85)
			(end -0.653 -1.85)
			(stroke
				(width 0.15)
				(type solid)
			)
			(fill yes)
			(layer "F.SilkS")
		)
		(fp_rect
			(start -1.85 -2)
			(end 1.8 1.95)
			(stroke
				(width 0.05)
				(type solid)
			)
			(fill no)
			(layer "F.CrtYd")
		)
		(fp_line
			(start 1.249 1.499)
			(end -1.25 1.499)
			(stroke
				(width 0.15)
				(type solid)
			)
			(layer "F.Fab")
		)
		(fp_line
			(start 1.249 -1.5)
			(end 1.249 1.499)
			(stroke
				(width 0.15)
				(type solid)
			)
			(layer "F.Fab")
		)
		(fp_line
			(start -1 -1.5)
			(end 1.249 -1.5)
			(stroke
				(width 0.15)
				(type solid)
			)
			(layer "F.Fab")
		)
		(fp_line
			(start -1.25 1.499)
			(end -1.25 -1.25)
			(stroke
				(width 0.15)
				(type solid)
			)
			(layer "F.Fab")
		)
		(fp_line
			(start -1.25 -1.25)
			(end -1 -1.5)
			(stroke
				(width 0.15)
				(type solid)
			)
			(layer "F.Fab")
		)
		(pad "1" smd oval
			(at -0.25 -1.5 180)
			(size 0.3 0.8)
			(layers "F.Cu" "F.Mask" "F.Paste")
			(net 707 "/USB PHY/FTDI_3V3")
			(pinfunction "VCCA")
			(pintype "power_in")
		)
		(pad "2" smd oval
			(at -1.25 -1 270)
			(size 0.3 0.8)
			(layers "F.Cu" "F.Mask" "F.Paste")
			(net 1015 "/USB PHY/FTDI_JTAG_TCK")
			(pinfunction "A1")
			(pintype "input")
		)
		(pad "3" smd oval
			(at -1.25 -0.5 270)
			(size 0.3 0.8)
			(layers "F.Cu" "F.Mask" "F.Paste")
			(net 1018 "/USB PHY/FTDI_JTAG_TMS")
			(pinfunction "A2")
			(pintype "input")
		)
		(pad "4" smd oval
			(at -1.25 0 270)
			(size 0.3 0.8)
			(layers "F.Cu" "F.Mask" "F.Paste")
			(net 1016 "/USB PHY/FTDI_JTAG_TDI")
			(pinfunction "A3")
			(pintype "input")
		)
		(pad "5" smd oval
			(at -1.25 0.494 270)
			(size 0.3 0.8)
			(layers "F.Cu" "F.Mask" "F.Paste")
			(net 1017 "/USB PHY/FTDI_JTAG_TDO")
			(pinfunction "A4Y")
			(pintype "output")
		)
		(pad "6" smd oval
			(at -1.25 0.994 270)
			(size 0.3 0.8)
			(layers "F.Cu" "F.Mask" "F.Paste")
			(net 1206 "unconnected-(U22-NC-Pad6)")
			(pinfunction "NC")
			(pintype "no_connect")
		)
		(pad "7" smd oval
			(at -0.25 1.499 180)
			(size 0.3 0.8)
			(layers "F.Cu" "F.Mask" "F.Paste")
			(net 1 "GND")
			(pinfunction "GND")
			(pintype "passive")
		)
		(pad "8" smd oval
			(at 0.244 1.499 180)
			(size 0.3 0.8)
			(layers "F.Cu" "F.Mask" "F.Paste")
			(net 799 "FTDI_DIS")
			(pinfunction "OE")
			(pintype "tri_state")
		)
		(pad "9" smd oval
			(at 1.249 0.994 270)
			(size 0.3 0.8)
			(layers "F.Cu" "F.Mask" "F.Paste")
			(net 1207 "unconnected-(U22-NC-Pad9)")
			(pinfunction "NC")
			(pintype "no_connect")
		)
		(pad "10" smd oval
			(at 1.249 0.494 270)
			(size 0.3 0.8)
			(layers "F.Cu" "F.Mask" "F.Paste")
			(net 371 "Net-(U22-B4)")
			(pinfunction "B4")
			(pintype "input")
		)
		(pad "11" smd oval
			(at 1.249 0 270)
			(size 0.3 0.8)
			(layers "F.Cu" "F.Mask" "F.Paste")
			(net 370 "Net-(U22-B3Y)")
			(pinfunction "B3Y")
			(pintype "output")
		)
		(pad "12" smd oval
			(at 1.249 -0.5 270)
			(size 0.3 0.8)
			(layers "F.Cu" "F.Mask" "F.Paste")
			(net 369 "Net-(U22-B2Y)")
			(pinfunction "B2Y")
			(pintype "output")
		)
		(pad "13" smd oval
			(at 1.249 -1 270)
			(size 0.3 0.8)
			(layers "F.Cu" "F.Mask" "F.Paste")
			(net 368 "Net-(U22-B1Y)")
			(pinfunction "B1Y")
			(pintype "output")
		)
		(pad "14" smd oval
			(at 0.244 -1.5 180)
			(size 0.3 0.8)
			(layers "F.Cu" "F.Mask" "F.Paste")
			(net 24 "+3V3")
			(pinfunction "VCCB")
			(pintype "power_in")
		)
		(pad "15" smd rect
			(at 0 0 180)
			(size 1 1.5)
			(layers "F.Cu" "F.Mask" "F.Paste")
			(net 1 "GND")
			(pinfunction "GND")
			(pintype "power_in")
		)
	)
	(footprint "antmicro-footprints:R_0402_1005Metric"
		(layer "F.Cu")
		(at 232.6 161.75 90)
		(descr "Resistor SMD 0402")
		(tags "resistor SMD 0402")
		(property "Reference" "R45"
			(at -2.95 0.45 90)
			(layer "F.SilkS")
			(effects
				(font
					(size 0.7 0.7)
					(thickness 0.15)
				)
				(justify left bottom)
			)
		)
		(property "Value" "R_1k_0402"
			(at 0 1.4 90)
			(layer "F.Fab")
			(effects
				(font
					(size 0.7 0.7)
					(thickness 0.15)
				)
				(justify left bottom)
			)
		)
		(property "Description" "SMD Chip Resistor, 1 kohm, ± 1%, 63 mW, 0402 [1005 Metric], Thick Film, General Purpose"
			(at 0 0 90)
			(layer "F.Fab")
			(hide yes)
			(effects
				(font
					(size 1.27 1.27)
					(thickness 0.15)
				)
			)
		)
		(property "Author" "Antmicro"
			(at 394.35 -70.85 0)
			(layer "F.Fab")
			(hide yes)
			(effects
				(font
					(size 1 1)
					(thickness 0.15)
				)
			)
		)
		(property "License" "Apache-2.0"
			(at 394.35 -70.85 0)
			(layer "F.Fab")
			(hide yes)
			(effects
				(font
					(size 1 1)
					(thickness 0.15)
				)
			)
		)
		(property "MPN" "CR0402-FX-1001GLF"
			(at 394.35 -70.85 0)
			(layer "F.Fab")
			(hide yes)
			(effects
				(font
					(size 1 1)
					(thickness 0.15)
				)
			)
		)
		(property "Manufacturer" "Bourns"
			(at 394.35 -70.85 0)
			(layer "F.Fab")
			(hide yes)
			(effects
				(font
					(size 1 1)
					(thickness 0.15)
				)
			)
		)
		(property "Tolerance" "1%"
			(at 394.35 -70.85 0)
			(layer "F.Fab")
			(hide yes)
			(effects
				(font
					(size 1 1)
					(thickness 0.15)
				)
			)
		)
		(property "Val" "1k"
			(at 394.35 -70.85 0)
			(layer "F.Fab")
			(hide yes)
			(effects
				(font
					(size 1 1)
					(thickness 0.15)
				)
			)
		)
		(sheetname "Power supply")
		(sheetfile "power-supply.kicad_sch")
		(attr smd)
		(fp_rect
			(start -0.925 -0.47)
			(end 0.925 0.47)
			(stroke
				(width 0.05)
				(type default)
			)
			(fill no)
			(layer "F.CrtYd")
		)
		(fp_rect
			(start -0.5 -0.25)
			(end 0.5 0.25)
			(stroke
				(width 0.15)
				(type solid)
			)
			(fill no)
			(layer "F.Fab")
		)
		(pad "1" smd roundrect
			(at -0.48 0 90)
			(size 0.59 0.64)
			(layers "F.Cu" "F.Mask" "F.Paste")
			(roundrect_rratio 0.25)
			(net 880 "/Power supply/VBUS_DIS")
			(pintype "passive")
		)
		(pad "2" smd roundrect
			(at 0.48 0 90)
			(size 0.59 0.64)
			(layers "F.Cu" "F.Mask" "F.Paste")
			(roundrect_rratio 0.25)
			(net 704 "/Power supply/USB_DBG_PD.VBUS")
			(pintype "passive")
		)
	)
	(footprint "antmicro-footprints:C_0402_1005Metric"
		(layer "F.Cu")
		(at 225.7 147.5 90)
		(descr "Capacitor SMD 0402")
		(tags "capacitor SMD 0402")
		(property "Reference" "C268"
			(at 0.75 0.35 90)
			(layer "F.SilkS")
			(effects
				(font
					(size 0.7 0.7)
					(thickness 0.15)
				)
				(justify left bottom)
			)
		)
		(property "Value" "C_100n_0402"
			(at 0 1.169 90)
			(layer "F.Fab")
			(effects
				(font
					(size 0.7 0.7)
					(thickness 0.15)
				)
				(justify left bottom)
			)
		)
		(property "Description" "SMD Multilayer Ceramic Capacitor, 0.1 µF, 50 V, 0402 [1005 Metric], ± 10%, X5R, GRM Series"
			(at 0 0 90)
			(layer "F.Fab")
			(hide yes)
			(effects
				(font
					(size 1.27 1.27)
					(thickness 0.15)
				)
			)
		)
		(property "Author" "Antmicro"
			(at 373.2 -78.2 0)
			(layer "F.Fab")
			(hide yes)
			(effects
				(font
					(size 1 1)
					(thickness 0.15)
				)
			)
		)
		(property "Dielectric" "X5R"
			(at 373.2 -78.2 0)
			(layer "F.Fab")
			(hide yes)
			(effects
				(font
					(size 1 1)
					(thickness 0.15)
				)
			)
		)
		(property "License" "Apache-2.0"
			(at 373.2 -78.2 0)
			(layer "F.Fab")
			(hide yes)
			(effects
				(font
					(size 1 1)
					(thickness 0.15)
				)
			)
		)
		(property "MPN" "GRM155R61H104KE14D"
			(at 373.2 -78.2 0)
			(layer "F.Fab")
			(hide yes)
			(effects
				(font
					(size 1 1)
					(thickness 0.15)
				)
			)
		)
		(property "Manufacturer" "Murata"
			(at 373.2 -78.2 0)
			(layer "F.Fab")
			(hide yes)
			(effects
				(font
					(size 1 1)
					(thickness 0.15)
				)
			)
		)
		(property "Val" "100n"
			(at 373.2 -78.2 0)
			(layer "F.Fab")
			(hide yes)
			(effects
				(font
					(size 1 1)
					(thickness 0.15)
				)
			)
		)
		(property "Voltage" "50V"
			(at 373.2 -78.2 0)
			(layer "F.Fab")
			(hide yes)
			(effects
				(font
					(size 1 1)
					(thickness 0.15)
				)
			)
		)
		(sheetname "HDMI + Ethernet")
		(sheetfile "hdmi-ethernet.kicad_sch")
		(attr smd)
		(fp_rect
			(start -0.925 -0.47)
			(end 0.925 0.47)
			(stroke
				(width 0.05)
				(type default)
			)
			(fill no)
			(layer "F.CrtYd")
		)
		(fp_line
			(start 0.504 -0.25)
			(end 0.504 0.248)
			(stroke
				(width 0.15)
				(type solid)
			)
			(layer "F.Fab")
		)
		(fp_line
			(start -0.494 -0.25)
			(end 0.504 -0.25)
			(stroke
				(width 0.15)
				(type solid)
			)
			(layer "F.Fab")
		)
		(fp_line
			(start 0.504 0.248)
			(end -0.494 0.248)
			(stroke
				(width 0.15)
				(type solid)
			)
			(layer "F.Fab")
		)
		(fp_line
			(start -0.494 0.248)
			(end -0.494 -0.25)
			(stroke
				(width 0.15)
				(type solid)
			)
			(layer "F.Fab")
		)
		(pad "1" smd roundrect
			(at -0.48 0 90)
			(size 0.59 0.64)
			(layers "F.Cu" "F.Mask" "F.Paste")
			(roundrect_rratio 0.25)
			(net 722 "/HDMI + Ethernet/ETH_VDDCR")
			(pintype "passive")
		)
		(pad "2" smd roundrect
			(at 0.48 0 90)
			(size 0.59 0.64)
			(layers "F.Cu" "F.Mask" "F.Paste")
			(roundrect_rratio 0.25)
			(net 1 "GND")
			(pintype "passive")
		)
	)
	(footprint "antmicro-footprints:R_0402_1005Metric"
		(layer "F.Cu")
		(at 161 184 90)
		(descr "Resistor SMD 0402")
		(tags "resistor SMD 0402")
		(property "Reference" "R364"
			(at 0.7 0.4 90)
			(layer "F.SilkS")
			(effects
				(font
					(size 0.7 0.7)
					(thickness 0.15)
				)
				(justify left bottom)
			)
		)
		(property "Value" "R_0R_0402"
			(at 0 1.4 90)
			(layer "F.Fab")
			(effects
				(font
					(size 0.7 0.7)
					(thickness 0.15)
				)
				(justify left bottom)
			)
		)
		(property "Description" "SMD Chip Resistor, Jumper, 0 ohm, 100 mW, 0402 [1005 Metric], Thick Film, General Purpose"
			(at 0 0 90)
			(layer "F.Fab")
			(hide yes)
			(effects
				(font
					(size 1.27 1.27)
					(thickness 0.15)
				)
			)
		)
		(property "Author" "Antmicro"
			(at 345 23 0)
			(layer "F.Fab")
			(hide yes)
			(effects
				(font
					(size 1 1)
					(thickness 0.15)
				)
			)
		)
		(property "Current" "1A"
			(at 345 23 0)
			(layer "F.Fab")
			(hide yes)
			(effects
				(font
					(size 1 1)
					(thickness 0.15)
				)
			)
		)
		(property "DNP" "DNP"
			(at 345 23 0)
			(layer "F.Fab")
			(hide yes)
			(effects
				(font
					(size 1 1)
					(thickness 0.15)
				)
			)
		)
		(property "License" "Apache-2.0"
			(at 345 23 0)
			(layer "F.Fab")
			(hide yes)
			(effects
				(font
					(size 1 1)
					(thickness 0.15)
				)
			)
		)
		(property "MPN" "ERJ2GE0R00X"
			(at 345 23 0)
			(layer "F.Fab")
			(hide yes)
			(effects
				(font
					(size 1 1)
					(thickness 0.15)
				)
			)
		)
		(property "Manufacturer" "Panasonic"
			(at 345 23 0)
			(layer "F.Fab")
			(hide yes)
			(effects
				(font
					(size 1 1)
					(thickness 0.15)
				)
			)
		)
		(property "Tolerance" ""
			(at 345 23 0)
			(layer "F.Fab")
			(hide yes)
			(effects
				(font
					(size 1 1)
					(thickness 0.15)
				)
			)
		)
		(property "Val" "0R"
			(at 345 23 0)
			(layer "F.Fab")
			(hide yes)
			(effects
				(font
					(size 1 1)
					(thickness 0.15)
				)
			)
		)
		(property "dnp" ""
			(at 345 23 0)
			(layer "F.Fab")
			(hide yes)
			(effects
				(font
					(size 1 1)
					(thickness 0.15)
				)
			)
		)
		(property "exclude_from_bom" ""
			(at 345 23 0)
			(layer "F.Fab")
			(hide yes)
			(effects
				(font
					(size 1 1)
					(thickness 0.15)
				)
			)
		)
		(sheetname "DC-DC Converters")
		(sheetfile "dc-dc.kicad_sch")
		(attr smd exclude_from_bom)
		(fp_rect
			(start -0.925 -0.47)
			(end 0.925 0.47)
			(stroke
				(width 0.05)
				(type default)
			)
			(fill no)
			(layer "F.CrtYd")
		)
		(fp_rect
			(start -0.5 -0.25)
			(end 0.5 0.25)
			(stroke
				(width 0.15)
				(type solid)
			)
			(fill no)
			(layer "F.Fab")
		)
		(pad "1" smd roundrect
			(at -0.48 0 90)
			(size 0.59 0.64)
			(layers "F.Cu" "F.Mask" "F.Paste")
			(roundrect_rratio 0.25)
			(net 577 "/DC-DC Converters/PB_CTRL.~{PB_CTRL_INT}")
			(pintype "passive")
		)
		(pad "2" smd roundrect
			(at 0.48 0 90)
			(size 0.59 0.64)
			(layers "F.Cu" "F.Mask" "F.Paste")
			(roundrect_rratio 0.25)
			(net 1340 "/SUP_MCU.SW_STATE")
			(pintype "passive")
		)
	)
)
